# S9S_MB_2U (Grand Teton) — schematic netlist excerpt (pin names and nets, part order shuffled) for the footprints in the layout excerpt that follows; sources: Cadence DE-HDL packaged netlist, KiCad conversion of 03242023_DA0F0TMBIJ0_F0T_Motherboard_J_brd_V01_OCP.brd

PC1868  Q_CAP  22UF 10V 20% X6S  pkg C0805  page 259 : A = P3V3_AUX ; B = GND
R571  Q_RES  2.2 1% CHIP  pkg 0603LF  page 206 : A = P3V3_DB2000_FB_VDD ; B = P3V3_DB2000_VDDR
R692  Q_RES  33.2 1% CHIP  pkg 0402LF  page 229 : A = I3C_SPD_DDRABCD_CPU0_LVC1_R_SDA ; B = I3C_SPD_DDRABCD_CPU0_LVC1_SDA

(kicad_pcb
	(version 20260206)
	(generator "pcbnew")
	(generator_version "10.0")
	(general
		(thickness 1.6)
		(legacy_teardrops no)
	)
	(paper "A4")
	(title_block
		(title "03242023_DA0F0TMBIJ0_F0T_Motherboard_J_brd_V01_OCP.brd")
		(comment 1 "Grand Teton / footprints 4949-4951 of 6105")
	)
	(layers
		(0 "F.Cu" signal "TOP")
		(4 "In1.Cu" signal "GND")
		(6 "In2.Cu" signal "IN1")
		(8 "In3.Cu" signal "GND1")
		(10 "In4.Cu" signal "IN2")
		(12 "In5.Cu" signal "GND2")
		(14 "In6.Cu" signal "IN3")
		(16 "In7.Cu" signal "GND3")
		(18 "In8.Cu" signal "VCC")
		(20 "In9.Cu" signal "VCC1")
		(22 "In10.Cu" signal "GND4")
		(24 "In11.Cu" signal "IN4")
		(26 "In12.Cu" signal "GND5")
		(28 "In13.Cu" signal "IN5")
		(30 "In14.Cu" signal "GND6")
		(32 "In15.Cu" signal "IN6")
		(34 "In16.Cu" signal "GND7")
		(2 "B.Cu" signal "BOTTOM")
		(9 "F.Adhes" user "F.Adhesive")
		(11 "B.Adhes" user "B.Adhesive")
		(13 "F.Paste" user "Package Geometry/Pastemask Top")
		(15 "B.Paste" user "Package Geometry/Pastemask Bottom")
		(5 "F.SilkS" user "Ref Des/Silkscreen Top")
		(7 "B.SilkS" user "Ref Des/Silkscreen Bottom")
		(1 "F.Mask" user "Board Geometry/Soldermask Top")
		(3 "B.Mask" user "Board Geometry/Soldermask Bottom")
		(17 "Dwgs.User" user "User.Drawings")
		(19 "Cmts.User" user "User.Comments")
		(21 "Eco1.User" user "User.Eco1")
		(23 "Eco2.User" user "User.Eco2")
		(25 "Edge.Cuts" user "Board Geometry/Outline")
		(27 "Margin" user)
		(31 "F.CrtYd" user "Package Geometry/Place Bound Top")
		(29 "B.CrtYd" user "Package Geometry/Place Bound Bottom")
		(35 "F.Fab" user "Ref Des/Assembly Top")
		(33 "B.Fab" user "Ref Des/Assembly Bottom")
	)
	(footprint ""
		(layer "B.Cu")
		(at 451.962012 -58.325512 -90)
		(property "Reference" "PC1868"
			(at 0 0 90)
			(layer "B.SilkS")
			(hide yes)
			(effects
				(font
					(size 1.27 1.27)
				)
				(justify mirror)
			)
		)
		(property "Value" ""
			(at 0 0 90)
			(layer "B.Fab")
			(effects
				(font
					(size 1.27 1.27)
				)
				(justify mirror)
			)
		)
		(duplicate_pad_numbers_are_jumpers no)
		(fp_line
			(start -1.524 0.762)
			(end 1.524 0.762)
			(stroke
				(width 0.1524)
				(type default)
			)
			(layer "B.SilkS")
		)
		(fp_line
			(start 1.524 0.762)
			(end 1.524 -0.762)
			(stroke
				(width 0.1524)
				(type default)
			)
			(layer "B.SilkS")
		)
		(fp_line
			(start -1.524 -0.762)
			(end -1.524 0.762)
			(stroke
				(width 0.1524)
				(type default)
			)
			(layer "B.SilkS")
		)
		(fp_line
			(start 1.524 -0.762)
			(end -1.524 -0.762)
			(stroke
				(width 0.1524)
				(type default)
			)
			(layer "B.SilkS")
		)
		(fp_line
			(start -1.1049 0.724916)
			(end -1.1049 -0.724916)
			(stroke
				(width 0.1)
				(type default)
			)
			(layer "B.Fab")
		)
		(fp_line
			(start 1.1049 0.724916)
			(end -1.1049 0.724916)
			(stroke
				(width 0.1)
				(type default)
			)
			(layer "B.Fab")
		)
		(fp_line
			(start -1.1049 -0.724916)
			(end 1.1049 -0.724916)
			(stroke
				(width 0.1)
				(type default)
			)
			(layer "B.Fab")
		)
		(fp_line
			(start 1.1049 -0.724916)
			(end 1.1049 0.724916)
			(stroke
				(width 0.1)
				(type default)
			)
			(layer "B.Fab")
		)
		(pad "1" smd rect
			(at 0.889 0 270)
			(size 1.016 1.27)
			(layers "B.Cu" "B.Mask" "B.Paste")
			(net "P3V3_AUX")
		)
		(pad "2" smd rect
			(at -0.889 0 270)
			(size 1.016 1.27)
			(layers "B.Cu" "B.Mask" "B.Paste")
			(net "GND")
		)
	)
	(footprint ""
		(layer "B.Cu")
		(at 291.586158 -153.944828)
		(property "Reference" "R692"
			(at 0 0 0)
			(layer "B.SilkS")
			(hide yes)
			(effects
				(font
					(size 1.27 1.27)
				)
				(justify mirror)
			)
		)
		(property "Value" ""
			(at 0 0 0)
			(layer "B.Fab")
			(effects
				(font
					(size 1.27 1.27)
				)
				(justify mirror)
			)
		)
		(duplicate_pad_numbers_are_jumpers no)
		(fp_line
			(start -0.7874 -0.4064)
			(end -0.7874 0.4064)
			(stroke
				(width 0.1524)
				(type default)
			)
			(layer "B.SilkS")
		)
		(fp_line
			(start -0.7874 0.4064)
			(end 0.7874 0.4064)
			(stroke
				(width 0.1524)
				(type default)
			)
			(layer "B.SilkS")
		)
		(fp_line
			(start 0.7874 -0.4064)
			(end -0.7874 -0.4064)
			(stroke
				(width 0.1524)
				(type default)
			)
			(layer "B.SilkS")
		)
		(fp_line
			(start 0.7874 0.4064)
			(end 0.7874 -0.4064)
			(stroke
				(width 0.1524)
				(type default)
			)
			(layer "B.SilkS")
		)
		(fp_line
			(start -0.67945 -0.3048)
			(end -0.67945 0.3048)
			(stroke
				(width 0.1)
				(type default)
			)
			(layer "B.Fab")
		)
		(fp_line
			(start -0.67945 0.3048)
			(end -0.120396 0.3048)
			(stroke
				(width 0.1)
				(type default)
			)
			(layer "B.Fab")
		)
		(fp_line
			(start -0.12065 -0.3048)
			(end -0.67945 -0.3048)
			(stroke
				(width 0.1)
				(type default)
			)
			(layer "B.Fab")
		)
		(fp_line
			(start -0.12065 -0.2794)
			(end -0.12065 -0.3048)
			(stroke
				(width 0.1)
				(type default)
			)
			(layer "B.Fab")
		)
		(fp_line
			(start -0.120396 0.2794)
			(end 0.12065 0.2794)
			(stroke
				(width 0.1)
				(type default)
			)
			(layer "B.Fab")
		)
		(fp_line
			(start -0.120396 0.3048)
			(end -0.120396 0.2794)
			(stroke
				(width 0.1)
				(type default)
			)
			(layer "B.Fab")
		)
		(fp_line
			(start 0.12065 -0.305054)
			(end 0.12065 -0.2794)
			(stroke
				(width 0.1)
				(type default)
			)
			(layer "B.Fab")
		)
		(fp_line
			(start 0.12065 -0.2794)
			(end -0.12065 -0.2794)
			(stroke
				(width 0.1)
				(type default)
			)
			(layer "B.Fab")
		)
		(fp_line
			(start 0.12065 0.2794)
			(end 0.12065 0.3048)
			(stroke
				(width 0.1)
				(type default)
			)
			(layer "B.Fab")
		)
		(fp_line
			(start 0.12065 0.3048)
			(end 0.67945 0.3048)
			(stroke
				(width 0.1)
				(type default)
			)
			(layer "B.Fab")
		)
		(fp_line
			(start 0.67945 -0.305054)
			(end 0.12065 -0.305054)
			(stroke
				(width 0.1)
				(type default)
			)
			(layer "B.Fab")
		)
		(fp_line
			(start 0.67945 0.3048)
			(end 0.67945 -0.305054)
			(stroke
				(width 0.1)
				(type default)
			)
			(layer "B.Fab")
		)
		(pad "1" smd circle
			(at 0.40005 0 180)
			(size 0 0)
			(layers "B.Cu" "B.Mask" "B.Paste")
			(net "I3C_SPD_DDRABCD_CPU0_LVC1_R_SDA")
		)
		(pad "2" smd circle
			(at -0.40005 0 180)
			(size 0 0)
			(layers "B.Cu" "B.Mask" "B.Paste")
			(net "I3C_SPD_DDRABCD_CPU0_LVC1_SDA")
		)
	)
	(footprint ""
		(layer "B.Cu")
		(at 234.230926 -120.851676 180)
		(property "Reference" "R571"
			(at 0 0 0)
			(layer "B.SilkS")
			(hide yes)
			(effects
				(font
					(size 1.27 1.27)
				)
				(justify mirror)
			)
		)
		(property "Value" ""
			(at 0 0 0)
			(layer "B.Fab")
			(effects
				(font
					(size 1.27 1.27)
				)
				(justify mirror)
			)
		)
		(duplicate_pad_numbers_are_jumpers no)
		(fp_line
			(start 1.2954 0.5842)
			(end 1.2954 -0.5842)
			(stroke
				(width 0.1524)
				(type default)
			)
			(layer "B.SilkS")
		)
		(fp_line
			(start 1.2954 -0.5842)
			(end -1.2954 -0.5842)
			(stroke
				(width 0.1524)
				(type default)
			)
			(layer "B.SilkS")
		)
		(fp_line
			(start -1.2954 0.5842)
			(end 1.2954 0.5842)
			(stroke
				(width 0.1524)
				(type default)
			)
			(layer "B.SilkS")
		)
		(fp_line
			(start -1.2954 -0.5842)
			(end -1.2954 0.5842)
			(stroke
				(width 0.1524)
				(type default)
			)
			(layer "B.SilkS")
		)
		(fp_line
			(start 1.1938 0.4064)
			(end 1.1938 -0.406654)
			(stroke
				(width 0.1)
				(type default)
			)
			(layer "B.Fab")
		)
		(fp_line
			(start 1.1938 -0.406654)
			(end 0.8636 -0.406654)
			(stroke
				(width 0.1)
				(type default)
			)
			(layer "B.Fab")
		)
		(fp_line
			(start 0.8636 0.4572)
			(end 0.8636 0.4318)
			(stroke
				(width 0.1)
				(type default)
			)
			(layer "B.Fab")
		)
		(fp_line
			(start 0.8636 0.4318)
			(end 0.8636 0.4064)
			(stroke
				(width 0.1)
				(type default)
			)
			(layer "B.Fab")
		)
		(fp_line
			(start 0.8636 0.4064)
			(end 1.1938 0.4064)
			(stroke
				(width 0.1)
				(type default)
			)
			(layer "B.Fab")
		)
		(fp_line
			(start 0.8636 -0.406654)
			(end 0.8636 -0.4572)
			(stroke
				(width 0.1)
				(type default)
			)
			(layer "B.Fab")
		)
		(fp_line
			(start 0.8636 -0.4572)
			(end -0.8636 -0.4572)
			(stroke
				(width 0.1)
				(type default)
			)
			(layer "B.Fab")
		)
		(fp_line
			(start -0.8636 0.4572)
			(end 0.8636 0.4572)
			(stroke
				(width 0.1)
				(type default)
			)
			(layer "B.Fab")
		)
		(fp_line
			(start -0.8636 0.4064)
			(end -0.8636 0.4572)
			(stroke
				(width 0.1)
				(type default)
			)
			(layer "B.Fab")
		)
		(fp_line
			(start -0.8636 -0.406654)
			(end -1.1938 -0.406654)
			(stroke
				(width 0.1)
				(type default)
			)
			(layer "B.Fab")
		)
		(fp_line
			(start -0.8636 -0.4572)
			(end -0.8636 -0.406654)
			(stroke
				(width 0.1)
				(type default)
			)
			(layer "B.Fab")
		)
		(fp_line
			(start -1.1938 0.4064)
			(end -0.8636 0.4064)
			(stroke
				(width 0.1)
				(type default)
			)
			(layer "B.Fab")
		)
		(fp_line
			(start -1.1938 -0.406654)
			(end -1.1938 0.4064)
			(stroke
				(width 0.1)
				(type default)
			)
			(layer "B.Fab")
		)
		(pad "1" smd rect
			(at 0.7366 0 90)
			(size 0.7112 0.8128)
			(layers "B.Cu" "B.Mask" "B.Paste")
			(net "P3V3_DB2000_FB_VDD")
		)
		(pad "2" smd rect
			(at -0.7366 0 90)
			(size 0.7112 0.8128)
			(layers "B.Cu" "B.Mask" "B.Paste")
			(net "P3V3_DB2000_VDDR")
		)
	)
)
